(kicad_pcb
	(version 20260206)
	(generator "pcbnew")
	(generator_version "10.0")
	(general
		(thickness 1.6)
		(legacy_teardrops no)
	)
	(paper "A4")
	(title_block
		(title "timecard-production-celestica-r4006 — R4006-B0001-02_R01.brd")
		(comment 1 "Time Appliance Project (Time Card) / footprints 217-222 of 1113")
	)
	(layers
		(0 "F.Cu" signal "TOP")
		(4 "In1.Cu" signal "L02_GND1")
		(6 "In2.Cu" signal "L03_SIG1")
		(8 "In3.Cu" signal "L04_GND2")
		(10 "In4.Cu" signal "L05_VCC1")
		(12 "In5.Cu" signal "L06_VCC2")
		(14 "In6.Cu" signal "L07_GND3")
		(16 "In7.Cu" signal "L08_SIG2")
		(18 "In8.Cu" signal "L09_GND4")
		(2 "B.Cu" signal "BOTTOM")
		(9 "F.Adhes" user "F.Adhesive")
		(11 "B.Adhes" user "B.Adhesive")
		(13 "F.Paste" user "Package Geometry/Pastemask Top")
		(15 "B.Paste" user "Package Geometry/Pastemask Bottom")
		(5 "F.SilkS" user "Ref Des/Silkscreen Top")
		(7 "B.SilkS" user "Ref Des/Silkscreen Bottom")
		(1 "F.Mask" user "Board Geometry/Soldermask Top")
		(3 "B.Mask" user "Board Geometry/Soldermask Bottom")
		(17 "Dwgs.User" user "User.Drawings")
		(19 "Cmts.User" user "User.Comments")
		(21 "Eco1.User" user "User.Eco1")
		(23 "Eco2.User" user "User.Eco2")
		(25 "Edge.Cuts" user "Board Geometry/Outline")
		(27 "Margin" user)
		(31 "F.CrtYd" user "Package Geometry/Place Bound Top")
		(29 "B.CrtYd" user "Package Geometry/Place Bound Bottom")
		(35 "F.Fab" user "Ref Des/Assembly Top")
		(33 "B.Fab" user "Ref Des/Assembly Bottom")
	)
	(footprint ""
		(layer "F.Cu")
		(at 93.726 -105.029 180)
		(property "Reference" "TP59"
			(at -0.8128 -0.16637 0)
			(unlocked yes)
			(layer "F.SilkS")
			(effects
				(font
					(size 0.7874 0.5842)
					(thickness 0.1524)
				)
				(justify left)
			)
		)
		(property "Value" ""
			(at 0 0 180)
			(layer "F.Fab")
			(effects
				(font
					(size 1.27 1.27)
				)
			)
		)
		(property "Device Type" "TP_PIONT-TP010CT020B030_PTH-TPA"
			(at -1.341882 0.996696 180)
			(unlocked yes)
			(layer "F.Fab")
			(hide yes)
			(effects
				(font
					(size 0.7874 0.5842)
					(thickness 0.1524)
				)
				(justify left)
			)
		)
		(duplicate_pad_numbers_are_jumpers no)
		(fp_poly
			(pts
				(arc
					(start -0.889 0)
					(mid 0.889 0)
					(end -0.889 0)
				)
			)
			(stroke
				(width 0)
				(type default)
			)
			(fill no)
			(layer "B.CrtYd")
		)
		(fp_poly
			(pts
				(arc
					(start -0.889 0)
					(mid 0.889 0)
					(end -0.889 0)
				)
			)
			(stroke
				(width 0)
				(type default)
			)
			(fill no)
			(layer "F.CrtYd")
		)
		(pad "1" thru_hole circle
			(at 0 0 180)
			(size 0.508 0.508)
			(drill 0.254)
			(layers "*.Cu" "*.Mask")
			(remove_unused_layers no)
			(net "XP3R3V_EN")
			(clearance 0.1016)
			(padstack
				(mode front_inner_back)
				(layer "Inner"
					(shape circle)
					(size 0.508 0.508)
					(clearance 0.1016)
				)
				(layer "B.Cu"
					(shape circle)
					(size 0.762 0.762)
					(clearance -0.0254)
				)
			)
		)
	)
	(footprint ""
		(layer "F.Cu")
		(at 95.631 -26.924)
		(property "Reference" "C291"
			(at -1.397 -1.73863 0)
			(unlocked yes)
			(layer "F.SilkS")
			(effects
				(font
					(size 0.7874 0.5842)
					(thickness 0.1524)
				)
			)
		)
		(property "Value" "VAL*"
			(at 0.0762 3.134106 0)
			(unlocked yes)
			(layer "F.Fab")
			(hide yes)
			(effects
				(font
					(size 0.7874 0.5842)
					(thickness 0.1524)
				)
			)
		)
		(property "Device Type" "CAPACITOR-G107-0F226-CM,22UF,2A"
			(at 0.0508 2.194306 0)
			(unlocked yes)
			(layer "F.Fab")
			(hide yes)
			(effects
				(font
					(size 0.7874 0.5842)
					(thickness 0.1524)
				)
			)
		)
		(property "User Part Number" "PARTNUM*"
			(at 0.1016 5.013706 0)
			(unlocked yes)
			(layer "Cmts.User")
			(hide yes)
			(effects
				(font
					(size 0.7874 0.5842)
					(thickness 0.1524)
				)
			)
		)
		(property "Tolerance" "TOL*"
			(at 0.0762 4.048506 0)
			(unlocked yes)
			(layer "Cmts.User")
			(hide yes)
			(effects
				(font
					(size 0.7874 0.5842)
					(thickness 0.1524)
				)
			)
		)
		(duplicate_pad_numbers_are_jumpers no)
		(fp_line
			(start -1.5748 -0.9398)
			(end -1.5748 0.9398)
			(stroke
				(width 0.1)
				(type default)
			)
			(layer "F.SilkS")
		)
		(fp_line
			(start -1.5748 0.9398)
			(end 1.5748 0.9398)
			(stroke
				(width 0.1)
				(type default)
			)
			(layer "F.SilkS")
		)
		(fp_line
			(start 1.5748 -0.9398)
			(end -1.5748 -0.9398)
			(stroke
				(width 0.1)
				(type default)
			)
			(layer "F.SilkS")
		)
		(fp_line
			(start 1.5748 0.9398)
			(end 1.5748 -0.9398)
			(stroke
				(width 0.1)
				(type default)
			)
			(layer "F.SilkS")
		)
		(fp_rect
			(start 1.5748 -0.9398)
			(end -1.5748 0.9398)
			(stroke
				(width 0)
				(type default)
			)
			(fill no)
			(layer "F.CrtYd")
		)
		(fp_line
			(start -1.016 -0.635)
			(end -1.016 0.635)
			(stroke
				(width 0.1)
				(type default)
			)
			(layer "F.Fab")
		)
		(fp_line
			(start -1.016 0.635)
			(end 1.016 0.635)
			(stroke
				(width 0.1)
				(type default)
			)
			(layer "F.Fab")
		)
		(fp_line
			(start 1.016 -0.635)
			(end -1.016 -0.635)
			(stroke
				(width 0.1)
				(type default)
			)
			(layer "F.Fab")
		)
		(fp_line
			(start 1.016 0.635)
			(end 1.016 -0.635)
			(stroke
				(width 0.1)
				(type default)
			)
			(layer "F.Fab")
		)
		(pad "1" smd rect
			(at -0.8382 0)
			(size 0.9652 1.3716)
			(layers "F.Cu" "F.Mask" "F.Paste")
			(net "XP2R5V_FPGA")
		)
		(pad "2" smd rect
			(at 0.8382 0)
			(size 0.9652 1.3716)
			(layers "F.Cu" "F.Mask" "F.Paste")
			(net "SG")
		)
		(zone
			(layer "F.Cu")
			(hatch none 0.5)
			(connect_pads
				(clearance 0)
			)
			(min_thickness 0.25)
			(keepout
				(tracks not_allowed)
				(vias allowed)
				(pads allowed)
				(copperpour not_allowed)
				(footprints allowed)
			)
			(placement
				(enabled no)
				(sheetname "")
			)
			(fill
				(thermal_gap 0.5)
				(thermal_bridge_width 0.5)
				(island_removal_mode 0)
			)
			(polygon
				(pts
					(xy 95.8596 -27.559) (xy 95.4024 -27.559) (xy 95.4024 -26.289) (xy 95.8596 -26.289)
				)
			)
		)
		(zone
			(layer "F.Cu")
			(hatch none 0.5)
			(connect_pads
				(clearance 0)
			)
			(min_thickness 0.25)
			(keepout
				(tracks allowed)
				(vias not_allowed)
				(pads allowed)
				(copperpour not_allowed)
				(footprints allowed)
			)
			(placement
				(enabled no)
				(sheetname "")
			)
			(fill
				(thermal_gap 0.5)
				(thermal_bridge_width 0.5)
				(island_removal_mode 0)
			)
			(polygon
				(pts
					(xy 95.8596 -27.559) (xy 95.4024 -27.559) (xy 95.4024 -26.289) (xy 95.8596 -26.289)
				)
			)
		)
	)
	(footprint ""
		(layer "F.Cu")
		(at 144.050004 -104.350058 -90)
		(property "Reference" "DS8"
			(at 0.718058 1.397254 90)
			(unlocked yes)
			(layer "F.SilkS")
			(effects
				(font
					(size 0.635 0.4064)
					(thickness 0.1524)
				)
			)
		)
		(property "Value" ""
			(at 0 0 270)
			(layer "F.Fab")
			(effects
				(font
					(size 1.27 1.27)
				)
			)
		)
		(property "Device Type" "OPTICAL-G170-10143-01"
			(at 0.1778 1.483081 270)
			(unlocked yes)
			(layer "F.Fab")
			(hide yes)
			(effects
				(font
					(size 0.786892 0.583946)
					(thickness 0.000001)
				)
			)
		)
		(property "User Part Number" "PARTNUM*"
			(at 0.1778 2.422881 270)
			(unlocked yes)
			(layer "Cmts.User")
			(hide yes)
			(effects
				(font
					(size 0.786892 0.583946)
					(thickness 0.000001)
				)
			)
		)
		(duplicate_pad_numbers_are_jumpers no)
		(fp_line
			(start -1.0668 1.3462)
			(end -2.3368 1.3462)
			(stroke
				(width 0.1)
				(type default)
			)
			(layer "F.SilkS")
		)
		(fp_line
			(start -1.7018 0.7112)
			(end -1.7018 1.9812)
			(stroke
				(width 0.1)
				(type default)
			)
			(layer "F.SilkS")
		)
		(fp_line
			(start -1.397508 0.704088)
			(end -1.397508 -0.704088)
			(stroke
				(width 0.1)
				(type default)
			)
			(layer "F.SilkS")
		)
		(fp_line
			(start 1.397508 0.704088)
			(end -1.397508 0.704088)
			(stroke
				(width 0.1)
				(type default)
			)
			(layer "F.SilkS")
		)
		(fp_line
			(start -1.397508 -0.704088)
			(end 1.397508 -0.704088)
			(stroke
				(width 0.1)
				(type default)
			)
			(layer "F.SilkS")
		)
		(fp_line
			(start 1.397508 -0.704088)
			(end 1.397508 0.704088)
			(stroke
				(width 0.1)
				(type default)
			)
			(layer "F.SilkS")
		)
		(fp_rect
			(start 1.905508 0.704088)
			(end 1.397508 -0.704088)
			(stroke
				(width 0)
				(type default)
			)
			(fill yes)
			(layer "F.SilkS")
		)
		(fp_rect
			(start 1.905508 0.958088)
			(end -1.651508 -0.958088)
			(stroke
				(width 0)
				(type default)
			)
			(fill no)
			(layer "F.CrtYd")
		)
		(fp_line
			(start -0.6858 1.0922)
			(end -1.9558 1.0922)
			(stroke
				(width 0.1)
				(type default)
			)
			(layer "F.Fab")
		)
		(fp_line
			(start -1.3208 0.4572)
			(end -1.3208 1.7272)
			(stroke
				(width 0.1)
				(type default)
			)
			(layer "F.Fab")
		)
		(fp_line
			(start -0.850138 0.450088)
			(end 0.850138 0.450088)
			(stroke
				(width 0.1)
				(type default)
			)
			(layer "F.Fab")
		)
		(fp_line
			(start 0.850138 0.450088)
			(end 0.850138 -0.450088)
			(stroke
				(width 0.1)
				(type default)
			)
			(layer "F.Fab")
		)
		(fp_line
			(start -0.850138 -0.450088)
			(end -0.850138 0.450088)
			(stroke
				(width 0.1)
				(type default)
			)
			(layer "F.Fab")
		)
		(fp_line
			(start 0.850138 -0.450088)
			(end -0.850138 -0.450088)
			(stroke
				(width 0.1)
				(type default)
			)
			(layer "F.Fab")
		)
		(fp_rect
			(start 0.850138 0.450088)
			(end 0.342138 -0.450088)
			(stroke
				(width 0)
				(type default)
			)
			(fill yes)
			(layer "F.Fab")
		)
		(fp_text user "A"
			(at -1.155192 1.683004 0)
			(unlocked yes)
			(layer "F.SilkS")
			(effects
				(font
					(size 0.635 0.4064)
					(thickness 0.1524)
				)
			)
		)
		(fp_text user "C"
			(at 2.400808 -0.983996 0)
			(unlocked yes)
			(layer "F.SilkS")
			(effects
				(font
					(size 0.635 0.4064)
					(thickness 0.1524)
				)
			)
		)
		(fp_text user "A"
			(at -1.49733 -0.7112 0)
			(unlocked yes)
			(layer "F.Fab")
			(effects
				(font
					(size 0.7874 0.5842)
					(thickness 0.1524)
				)
			)
		)
		(fp_text user "C"
			(at 1.773428 -0.856996 0)
			(unlocked yes)
			(layer "F.Fab")
			(effects
				(font
					(size 0.7874 0.5842)
					(thickness 0.1524)
				)
			)
		)
		(pad "A" smd rect
			(at -0.749808 0 270)
			(size 0.7874 0.7874)
			(layers "F.Cu" "F.Mask" "F.Paste")
			(net "UNNAMED_14_OPTICAL_I142_A")
		)
		(pad "C" smd rect
			(at 0.749808 0 270)
			(size 0.7874 0.7874)
			(layers "F.Cu" "F.Mask" "F.Paste")
			(net "SG")
		)
	)
	(footprint ""
		(layer "F.Cu")
		(at 50.74158 -15.5194 -90)
		(property "Reference" "R354"
			(at -3.4036 -0.09779 90)
			(unlocked yes)
			(layer "F.SilkS")
			(effects
				(font
					(size 0.7874 0.5842)
					(thickness 0.1524)
				)
			)
		)
		(property "Value" "VAL*"
			(at 0.02032 2.13233 270)
			(unlocked yes)
			(layer "F.Fab")
			(hide yes)
			(effects
				(font
					(size 0.7874 0.5842)
					(thickness 0.1524)
				)
			)
		)
		(property "Tolerance" "TOL*"
			(at 0.044704 3.05435 270)
			(unlocked yes)
			(layer "Cmts.User")
			(hide yes)
			(effects
				(font
					(size 0.7874 0.5842)
					(thickness 0.1524)
				)
			)
		)
		(property "User Part Number" "PARTNUM*"
			(at 0.02032 4.024884 270)
			(unlocked yes)
			(layer "Cmts.User")
			(hide yes)
			(effects
				(font
					(size 0.7874 0.5842)
					(thickness 0.1524)
				)
			)
		)
		(property "Device Type" "RESISTOR-G155-133R0-01,33OHM,1%"
			(at 0.008382 1.210564 270)
			(unlocked yes)
			(layer "F.Fab")
			(hide yes)
			(effects
				(font
					(size 0.7874 0.5842)
					(thickness 0.1524)
				)
			)
		)
		(duplicate_pad_numbers_are_jumpers no)
		(fp_line
			(start -1.143 0.5588)
			(end 1.143 0.5588)
			(stroke
				(width 0.1)
				(type default)
			)
			(layer "F.SilkS")
		)
		(fp_line
			(start 1.143 0.5588)
			(end 1.143 -0.5588)
			(stroke
				(width 0.1)
				(type default)
			)
			(layer "F.SilkS")
		)
		(fp_line
			(start -1.143 -0.5588)
			(end -1.143 0.5588)
			(stroke
				(width 0.1)
				(type default)
			)
			(layer "F.SilkS")
		)
		(fp_line
			(start 1.143 -0.5588)
			(end -1.143 -0.5588)
			(stroke
				(width 0.1)
				(type default)
			)
			(layer "F.SilkS")
		)
		(fp_rect
			(start 1.143 0.5588)
			(end -1.143 -0.5588)
			(stroke
				(width 0)
				(type default)
			)
			(fill no)
			(layer "F.CrtYd")
		)
		(fp_line
			(start -0.508 0.3048)
			(end 0.508 0.3048)
			(stroke
				(width 0.1)
				(type default)
			)
			(layer "F.Fab")
		)
		(fp_line
			(start 0.508 0.3048)
			(end 0.508 -0.3048)
			(stroke
				(width 0.1)
				(type default)
			)
			(layer "F.Fab")
		)
		(fp_line
			(start -0.508 -0.3048)
			(end -0.508 0.3048)
			(stroke
				(width 0.1)
				(type default)
			)
			(layer "F.Fab")
		)
		(fp_line
			(start 0.508 -0.3048)
			(end -0.508 -0.3048)
			(stroke
				(width 0.1)
				(type default)
			)
			(layer "F.Fab")
		)
		(pad "1" smd rect
			(at -0.5334 0 270)
			(size 0.7112 0.6096)
			(layers "F.Cu" "F.Mask" "F.Paste")
			(net "FPGA_OUT_I2C_BUFFER_EN")
		)
		(pad "2" smd rect
			(at 0.5334 0 270)
			(size 0.7112 0.6096)
			(layers "F.Cu" "F.Mask" "F.Paste")
			(net "UNNAMED_3_G2201019801_I100_EN")
		)
		(zone
			(layer "F.Cu")
			(hatch none 0.5)
			(connect_pads
				(clearance 0)
			)
			(min_thickness 0.25)
			(keepout
				(tracks allowed)
				(vias not_allowed)
				(pads allowed)
				(copperpour not_allowed)
				(footprints allowed)
			)
			(placement
				(enabled no)
				(sheetname "")
			)
			(fill
				(thermal_gap 0.5)
				(thermal_bridge_width 0.5)
				(island_removal_mode 0)
			)
			(polygon
				(pts
					(xy 50.43678 -15.4432) (xy 51.04638 -15.4432) (xy 51.04638 -15.5956) (xy 50.43678 -15.5956)
				)
			)
		)
	)
	(footprint ""
		(layer "F.Cu")
		(at 101.4476 -83.5914)
		(property "Reference" "R461"
			(at -2.5146 -0.69723 0)
			(unlocked yes)
			(layer "F.SilkS")
			(effects
				(font
					(size 0.7874 0.5842)
					(thickness 0.1524)
				)
			)
		)
		(property "Value" "VAL*"
			(at 0.02032 2.13233 0)
			(unlocked yes)
			(layer "F.Fab")
			(hide yes)
			(effects
				(font
					(size 0.7874 0.5842)
					(thickness 0.1524)
				)
			)
		)
		(property "Tolerance" "TOL*"
			(at 0.044704 3.05435 0)
			(unlocked yes)
			(layer "Cmts.User")
			(hide yes)
			(effects
				(font
					(size 0.7874 0.5842)
					(thickness 0.1524)
				)
			)
		)
		(property "User Part Number" "PARTNUM*"
			(at 0.02032 4.024884 0)
			(unlocked yes)
			(layer "Cmts.User")
			(hide yes)
			(effects
				(font
					(size 0.7874 0.5842)
					(thickness 0.1524)
				)
			)
		)
		(property "Device Type" "RESISTOR-G155-133R0-01,33OHM,1%"
			(at 0.008382 1.210564 0)
			(unlocked yes)
			(layer "F.Fab")
			(hide yes)
			(effects
				(font
					(size 0.7874 0.5842)
					(thickness 0.1524)
				)
			)
		)
		(duplicate_pad_numbers_are_jumpers no)
		(fp_line
			(start -1.143 -0.5588)
			(end -1.143 0.5588)
			(stroke
				(width 0.1)
				(type default)
			)
			(layer "F.SilkS")
		)
		(fp_line
			(start -1.143 0.5588)
			(end 1.143 0.5588)
			(stroke
				(width 0.1)
				(type default)
			)
			(layer "F.SilkS")
		)
		(fp_line
			(start 1.143 -0.5588)
			(end -1.143 -0.5588)
			(stroke
				(width 0.1)
				(type default)
			)
			(layer "F.SilkS")
		)
		(fp_line
			(start 1.143 0.5588)
			(end 1.143 -0.5588)
			(stroke
				(width 0.1)
				(type default)
			)
			(layer "F.SilkS")
		)
		(fp_poly
			(pts
				(xy -1.143 0.5588) (xy 1.143 0.5588) (xy 1.143 -0.5588) (xy -1.143 -0.5588)
			)
			(stroke
				(width 0)
				(type default)
			)
			(fill no)
			(layer "F.CrtYd")
		)
		(fp_line
			(start -0.508 -0.3048)
			(end -0.508 0.3048)
			(stroke
				(width 0.1)
				(type default)
			)
			(layer "F.Fab")
		)
		(fp_line
			(start -0.508 0.3048)
			(end 0.508 0.3048)
			(stroke
				(width 0.1)
				(type default)
			)
			(layer "F.Fab")
		)
		(fp_line
			(start 0.508 -0.3048)
			(end -0.508 -0.3048)
			(stroke
				(width 0.1)
				(type default)
			)
			(layer "F.Fab")
		)
		(fp_line
			(start 0.508 0.3048)
			(end 0.508 -0.3048)
			(stroke
				(width 0.1)
				(type default)
			)
			(layer "F.Fab")
		)
		(pad "1" smd rect
			(at -0.5334 0)
			(size 0.7112 0.6096)
			(layers "F.Cu" "F.Mask" "F.Paste")
			(net "FPGA_OUT_MUX2_SEL")
		)
		(pad "2" smd rect
			(at 0.5334 0)
			(size 0.7112 0.6096)
			(layers "F.Cu" "F.Mask" "F.Paste")
			(net "MUX2_SEL")
		)
		(zone
			(layer "F.Cu")
			(hatch none 0.5)
			(connect_pads
				(clearance 0)
			)
			(min_thickness 0.25)
			(keepout
				(tracks allowed)
				(vias not_allowed)
				(pads allowed)
				(copperpour not_allowed)
				(footprints allowed)
			)
			(placement
				(enabled no)
				(sheetname "")
			)
			(fill
				(thermal_gap 0.5)
				(thermal_bridge_width 0.5)
				(island_removal_mode 0)
			)
			(polygon
				(pts
					(xy 101.3714 -83.2866) (xy 101.5238 -83.2866) (xy 101.5238 -83.8962) (xy 101.3714 -83.8962)
				)
			)
		)
		(zone
			(layer "F.Cu")
			(hatch none 0.5)
			(connect_pads
				(clearance 0)
			)
			(min_thickness 0.25)
			(keepout
				(tracks not_allowed)
				(vias allowed)
				(pads allowed)
				(copperpour not_allowed)
				(footprints allowed)
			)
			(placement
				(enabled no)
				(sheetname "")
			)
			(fill
				(thermal_gap 0.5)
				(thermal_bridge_width 0.5)
				(island_removal_mode 0)
			)
			(polygon
				(pts
					(xy 101.3714 -83.2866) (xy 101.5238 -83.2866) (xy 101.5238 -83.8962) (xy 101.3714 -83.8962)
				)
			)
		)
	)
	(footprint ""
		(layer "F.Cu")
		(at 135.3312 -66.8528 90)
		(property "Reference" "R190"
			(at -4.8768 0.34417 90)
			(unlocked yes)
			(layer "F.SilkS")
			(effects
				(font
					(size 0.7874 0.5842)
					(thickness 0.1524)
				)
			)
		)
		(property "Value" "VAL*"
			(at 0.02032 2.13233 90)
			(unlocked yes)
			(layer "F.Fab")
			(hide yes)
			(effects
				(font
					(size 0.7874 0.5842)
					(thickness 0.1524)
				)
			)
		)
		(property "Tolerance" "TOL*"
			(at 0.044704 3.05435 90)
			(unlocked yes)
			(layer "Cmts.User")
			(hide yes)
			(effects
				(font
					(size 0.7874 0.5842)
					(thickness 0.1524)
				)
			)
		)
		(property "User Part Number" "PARTNUM*"
			(at 0.02032 4.024884 90)
			(unlocked yes)
			(layer "Cmts.User")
			(hide yes)
			(effects
				(font
					(size 0.7874 0.5842)
					(thickness 0.1524)
				)
			)
		)
		(property "Device Type" "RESISTOR-G155-03241-01,3.24KOHA"
			(at 0.008382 1.210564 90)
			(unlocked yes)
			(layer "F.Fab")
			(hide yes)
			(effects
				(font
					(size 0.7874 0.5842)
					(thickness 0.1524)
				)
			)
		)
		(duplicate_pad_numbers_are_jumpers no)
		(fp_line
			(start 1.143 -0.5588)
			(end -1.143 -0.5588)
			(stroke
				(width 0.1)
				(type default)
			)
			(layer "F.SilkS")
		)
		(fp_line
			(start -1.143 -0.5588)
			(end -1.143 0.5588)
			(stroke
				(width 0.1)
				(type default)
			)
			(layer "F.SilkS")
		)
		(fp_line
			(start 1.143 0.5588)
			(end 1.143 -0.5588)
			(stroke
				(width 0.1)
				(type default)
			)
			(layer "F.SilkS")
		)
		(fp_line
			(start -1.143 0.5588)
			(end 1.143 0.5588)
			(stroke
				(width 0.1)
				(type default)
			)
			(layer "F.SilkS")
		)
		(fp_rect
			(start 1.143 0.5588)
			(end -1.143 -0.5588)
			(stroke
				(width 0)
				(type default)
			)
			(fill no)
			(layer "F.CrtYd")
		)
		(fp_line
			(start 0.508 -0.3048)
			(end -0.508 -0.3048)
			(stroke
				(width 0.1)
				(type default)
			)
			(layer "F.Fab")
		)
		(fp_line
			(start -0.508 -0.3048)
			(end -0.508 0.3048)
			(stroke
				(width 0.1)
				(type default)
			)
			(layer "F.Fab")
		)
		(fp_line
			(start 0.508 0.3048)
			(end 0.508 -0.3048)
			(stroke
				(width 0.1)
				(type default)
			)
			(layer "F.Fab")
		)
		(fp_line
			(start -0.508 0.3048)
			(end 0.508 0.3048)
			(stroke
				(width 0.1)
				(type default)
			)
			(layer "F.Fab")
		)
		(pad "1" smd rect
			(at -0.5334 0 90)
			(size 0.7112 0.6096)
			(layers "F.Cu" "F.Mask" "F.Paste")
			(net "SG")
		)
		(pad "2" smd rect
			(at 0.5334 0 90)
			(size 0.7112 0.6096)
			(layers "F.Cu" "F.Mask" "F.Paste")
			(net "XP1R8V_FB")
		)
		(zone
			(layer "F.Cu")
			(hatch none 0.5)
			(connect_pads
				(clearance 0)
			)
			(min_thickness 0.25)
			(keepout
				(tracks allowed)
				(vias not_allowed)
				(pads allowed)
				(copperpour not_allowed)
				(footprints allowed)
			)
			(placement
				(enabled no)
				(sheetname "")
			)
			(fill
				(thermal_gap 0.5)
				(thermal_bridge_width 0.5)
				(island_removal_mode 0)
			)
			(polygon
				(pts
					(xy 135.636 -66.929) (xy 135.0264 -66.929) (xy 135.0264 -66.7766) (xy 135.636 -66.7766)
				)
			)
		)
	)
)
